# BASEBOARD_FAB2 (Tioga Pass) — schematic netlist excerpt (pin names and nets, part order shuffled) for the footprints in the layout excerpt that follows; sources: Cadence DE-HDL packaged netlist, KiCad conversion of Wiwynn_Tioga_Pass_MB.brd

J9L2  SCONN288_H44441003  SCONN  pkg PIP  page 86
  \12v\(1)  = P12V_NVDIMM_KLM
  VSS(93)  = GND
  DQ(4)  = M_L_DQ<4>
  VSS(92)  = GND
  DQ(0)  = M_L_DQ<0>
  VSS(91)  = GND
  DQS9P  = M_L_DQS_DP<9>
  DQS9N  = M_L_DQS_DN<9>
  VSS(90)  = GND
  DQ(6)  = M_L_DQ<6>
  VSS(89)  = GND
  DQ(2)  = M_L_DQ<2>
  VSS(88)  = GND
  DQ(12)  = M_L_DQ<12>
  VSS(87)  = GND
  DQ(8)  = M_L_DQ<8>
  VSS(86)  = GND
  DQS10P  = M_L_DQS_DP<10>
  DQS10N  = M_L_DQS_DN<10>
  VSS(85)  = GND
  DQ(14)  = M_L_DQ<14>
  VSS(84)  = GND
  DQ(10)  = M_L_DQ<10>
  VSS(83)  = GND
  DQ(20)  = M_L_DQ<20>
  VSS(82)  = GND
  DQ(16)  = M_L_DQ<16>
  VSS(81)  = GND
  DQS11P  = M_L_DQS_DP<11>
  DQS11N  = M_L_DQS_DN<11>
  VSS(80)  = GND
  DQ(22)  = M_L_DQ<22>
  VSS(79)  = GND
  DQ(18)  = M_L_DQ<18>
  VSS(78)  = GND
  DQ(28)  = M_L_DQ<28>
  VSS(77)  = GND
  DQ(24)  = M_L_DQ<24>
  VSS(76)  = GND
  DQS12P  = M_L_DQS_DP<12>
  DQS12N  = M_L_DQS_DN<12>
  VSS(75)  = GND
  DQ(30)  = M_L_DQ<30>
  VSS(74)  = GND
  DQ(26)  = M_L_DQ<26>
  VSS(73)  = GND
  CB(4)  = M_L_ECC<4>
  VSS(72)  = GND
  CB(0)  = M_L_ECC<0>
  VSS(71)  = GND
  DQS17P  = M_L_DQS_DP<17>
  DQS17N  = M_L_DQS_DN<17>
  VSS(70)  = GND
  CB(6)  = M_L_ECC<6>
  VSS(69)  = GND
  CB(2)  = M_L_ECC<2>
  VSS(68)  = GND
  RESET_N  = M_KLM_RST_N
  VDD(25)  = PVDDQ_KLM
  CKE(0)  = M_L_CKE<2>
  VDD(24)  = PVDDQ_KLM
  ACT_N  = M_L_ACT_N
  BG(0)  = M_L_BG<0>
  VDD(23)  = PVDDQ_KLM
  A12  = M_L_MA<12>
  A9  = M_L_MA<9>
  VDD(22)  = PVDDQ_KLM
  A8  = M_L_MA<8>
  A6  = M_L_MA<6>
  VDD(21)  = PVDDQ_KLM
  A3  = M_L_MA<3>
  A1  = M_L_MA<1>
  VDD(20)  = PVDDQ_KLM
  CK0P  = M_L_CLK_DP<2>
  CK0N  = M_L_CLK_DN<2>
  VDD(19)  = PVDDQ_KLM
  VTT(1)  = PVTT_KLM
  EVENT_N  = FM_DIMM_EVENT_COD_N
  A0  = M_L_MA<0>
  VDD(18)  = PVDDQ_KLM
  BA(0)  = M_L_BA<0>
  A16_RAS_N  = M_L_MA<16>
  VDD(17)  = PVDDQ_KLM
  S0_N  = M_L_CS_N<4>
  VDD(16)  = PVDDQ_KLM
  A15_CAS_N  = M_L_MA<15>
  ODT(0)  = M_L_ODT<2>
  VDD(15)  = PVDDQ_KLM
  S1_N  = M_L_CS_N<5>
  VDD(14)  = PVDDQ_KLM
  ODT(1)  = M_L_ODT<3>
  VDD(13)  = PVDDQ_KLM
  S2_N_C(0)  = M_L_CS_N<6>
  VSS(67)  = GND
  DQ(36)  = M_L_DQ<36>
  VSS(66)  = GND
  DQ(32)  = M_L_DQ<32>
  VSS(65)  = GND
  DQS13P  = M_L_DQS_DP<13>
  DQS13N  = M_L_DQS_DN<13>
  VSS(64)  = GND
  DQ(38)  = M_L_DQ<38>
  VSS(63)  = GND
  DQ(34)  = M_L_DQ<34>
  VSS(62)  = GND
  DQ(44)  = M_L_DQ<44>
  VSS(61)  = GND
  DQ(40)  = M_L_DQ<40>
  VSS(60)  = GND
  DQS14P  = M_L_DQS_DP<14>
  DQS14N  = M_L_DQS_DN<14>
  VSS(59)  = GND
  DQ(46)  = M_L_DQ<46>
  VSS(58)  = GND
  DQ(42)  = M_L_DQ<42>
  VSS(57)  = GND
  DQ(52)  = M_L_DQ<52>
  VSS(56)  = GND
  DQ(48)  = M_L_DQ<48>
  VSS(55)  = GND
  DQS15P  = M_L_DQS_DP<15>
  DQS15N  = M_L_DQS_DN<15>
  VSS(54)  = GND
  DQ(54)  = M_L_DQ<54>
  VSS(53)  = GND
  DQ(50)  = M_L_DQ<50>
  VSS(52)  = GND
  DQ(60)  = M_L_DQ<60>
  VSS(51)  = GND
  DQ(56)  = M_L_DQ<56>
  VSS(50)  = GND
  DQS16P  = M_L_DQS_DP<16>
  DQS16N  = M_L_DQS_DN<16>
  VSS(49)  = GND
  DQ(62)  = M_L_DQ<62>
  VSS(48)  = GND
  DQ(58)  = M_L_DQ<58>
  VSS(47)  = GND
  SA(0)  = PVPP_KLM
  SA(1)  = PVPP_KLM
  SCL  = SMB_DDR_KLM_VPP_SCL
  VPP(4)  = PVPP_KLM
  VPP(3)  = PVPP_KLM
  RFU(2)  = TP_CH_L_DIMM0_RFU_2
  \12v\(0)  = P12V_NVDIMM_KLM
  VREFCA  = M_L_VREF
  VSS(46)  = GND
  DQ(5)  = M_L_DQ<5>
  VSS(45)  = GND
  DQ(1)  = M_L_DQ<1>
  VSS(44)  = GND
  DQS0N  = M_L_DQS_DN<0>
  DQS0P  = M_L_DQS_DP<0>
  VSS(43)  = GND
  DQ(7)  = M_L_DQ<7>
  VSS(42)  = GND
  DQ(3)  = M_L_DQ<3>
  VSS(41)  = GND
  DQ(13)  = M_L_DQ<13>
  VSS(40)  = GND
  DQ(9)  = M_L_DQ<9>
  VSS(39)  = GND
  DQS1N  = M_L_DQS_DN<1>
  DQS1P  = M_L_DQS_DP<1>
  VSS(38)  = GND
  DQ(15)  = M_L_DQ<15>
  VSS(37)  = GND
  DQ(11)  = M_L_DQ<11>
  VSS(36)  = GND
  DQ(21)  = M_L_DQ<21>
  VSS(35)  = GND
  DQ(17)  = M_L_DQ<17>
  VSS(34)  = GND
  DQS2N  = M_L_DQS_DN<2>
  DQS2P  = M_L_DQS_DP<2>
  VSS(33)  = GND
  DQ(23)  = M_L_DQ<23>
  VSS(32)  = GND
  DQ(19)  = M_L_DQ<19>
  VSS(31)  = GND
  DQ(29)  = M_L_DQ<29>
  VSS(30)  = GND
  DQ(25)  = M_L_DQ<25>
  VSS(29)  = GND
  DQS3N  = M_L_DQS_DN<3>
  DQS3P  = M_L_DQS_DP<3>
  VSS(28)  = GND
  DQ(31)  = M_L_DQ<31>
  VSS(27)  = GND
  DQ(27)  = M_L_DQ<27>
  VSS(26)  = GND
  CB(5)  = M_L_ECC<5>
  VSS(25)  = GND
  CB(1)  = M_L_ECC<1>
  VSS(24)  = GND
  DQS8N  = M_L_DQS_DN<8>
  DQS8P  = M_L_DQS_DP<8>
  VSS(23)  = GND
  CB(7)  = M_L_ECC<7>
  VSS(22)  = GND
  CB(3)  = M_L_ECC<3>
  VSS(21)  = GND
  CKE(1)  = M_L_CKE<3>
  VDD(12)  = PVDDQ_KLM
  RFU(0)  = TP_CH_L_DIMM0_RFU_0
  VDD(11)  = PVDDQ_KLM
  BG(1)  = M_L_BG<1>
  ALERT_N  = M_L_ALERT_N
  VDD(10)  = PVDDQ_KLM
  A11  = M_L_MA<11>
  A7  = M_L_MA<7>
  VDD(9)  = PVDDQ_KLM
  A5  = M_L_MA<5>
  A4  = M_L_MA<4>
  VDD(8)  = PVDDQ_KLM
  A2  = M_L_MA<2>
  VDD(7)  = PVDDQ_KLM
  CK1P  = M_L_CLK_DP<3>
  CK1N  = M_L_CLK_DN<3>
  VDD(6)  = PVDDQ_KLM
  VTT(0)  = PVTT_KLM
  PAR  = M_L_PAR
  VDD(5)  = PVDDQ_KLM
  BA(1)  = M_L_BA<1>
  A10  = M_L_MA<10>
  VDD(4)  = PVDDQ_KLM
  RFU(1)  = TP_CH_L_DIMM0_RFU_1
  A14_WE_N  = M_L_MA<14>
  VDD(3)  = PVDDQ_KLM
  SAVE_N_NC  = FM_ADR_COMPLETE_KLM_N
  VDD(2)  = PVDDQ_KLM
  A13  = M_L_MA<13>
  VDD(1)  = PVDDQ_KLM
  A17  = M_L_MA<17>
  C(2)  = M_L_C<2>
  VDD(0)  = PVDDQ_KLM
  S3_N_C(1)  = M_L_CS_N<7>
  SA(2)  = GND
  VSS(20)  = GND
  DQ(37)  = M_L_DQ<37>
  VSS(19)  = GND
  DQ(33)  = M_L_DQ<33>
  VSS(18)  = GND
  DQS4N  = M_L_DQS_DN<4>
  DQS4P  = M_L_DQS_DP<4>
  VSS(17)  = GND
  DQ(39)  = M_L_DQ<39>
  VSS(16)  = GND
  DQ(35)  = M_L_DQ<35>
  VSS(15)  = GND
  DQ(45)  = M_L_DQ<45>
  VSS(14)  = GND
  DQ(41)  = M_L_DQ<41>
  VSS(13)  = GND
  DQS5N  = M_L_DQS_DN<5>
  DQS5P  = M_L_DQS_DP<5>
  VSS(12)  = GND
  DQ(47)  = M_L_DQ<47>
  VSS(11)  = GND
  DQ(43)  = M_L_DQ<43>
  VSS(10)  = GND
  DQ(53)  = M_L_DQ<53>
  VSS(9)  = GND
  DQ(49)  = M_L_DQ<49>
  VSS(8)  = GND
  DQS6N  = M_L_DQS_DN<6>
  DQS6P  = M_L_DQS_DP<6>
  VSS(7)  = GND
  DQ(55)  = M_L_DQ<55>
  VSS(6)  = GND
  DQ(51)  = M_L_DQ<51>
  VSS(5)  = GND
  DQ(61)  = M_L_DQ<61>
  VSS(4)  = GND
  DQ(57)  = M_L_DQ<57>
  VSS(3)  = GND
  DQS7N  = M_L_DQS_DN<7>
  DQS7P  = M_L_DQS_DP<7>
  VSS(2)  = GND
  DQ(63)  = M_L_DQ<63>
  VSS(1)  = GND
  DQ(59)  = M_L_DQ<59>
  VSS(0)  = GND
  VDDSPD  = PVPP_KLM
  SDA  = SMB_DDR_KLM_VPP_SDA
  VPP(1)  = PVPP_KLM
  VPP(0)  = PVPP_KLM
  VPP(2)  = PVPP_KLM

(kicad_pcb
	(version 20260206)
	(generator "pcbnew")
	(generator_version "10.0")
	(general
		(thickness 1.6)
		(legacy_teardrops no)
	)
	(paper "A4")
	(title_block
		(title "Wiwynn_Tioga_Pass_MB.brd")
		(comment 1 "Tioga Pass / footprint 4281 of 4770 (J9L2), pads 202-249 of 291")
	)
	(layers
		(0 "F.Cu" signal "TOP")
		(4 "In1.Cu" signal "L2GND")
		(6 "In2.Cu" signal "L3")
		(8 "In3.Cu" signal "L4GND")
		(10 "In4.Cu" signal "L5")
		(12 "In5.Cu" signal "L6GND")
		(14 "In6.Cu" signal "L7VCC")
		(16 "In7.Cu" signal "L8VCC")
		(18 "In8.Cu" signal "L9GND")
		(20 "In9.Cu" signal "L10")
		(22 "In10.Cu" signal "L11GND")
		(24 "In11.Cu" signal "L12")
		(26 "In12.Cu" signal "L13GND")
		(2 "B.Cu" signal "BOTTOM")
		(9 "F.Adhes" user "F.Adhesive")
		(11 "B.Adhes" user "B.Adhesive")
		(13 "F.Paste" user "Package Geometry/Pastemask Top")
		(15 "B.Paste" user "Package Geometry/Pastemask Bottom")
		(5 "F.SilkS" user "Ref Des/Silkscreen Top")
		(7 "B.SilkS" user "Ref Des/Silkscreen Bottom")
		(1 "F.Mask" user "Board Geometry/Soldermask Top")
		(3 "B.Mask" user "Board Geometry/Soldermask Bottom")
		(17 "Dwgs.User" user "User.Drawings")
		(19 "Cmts.User" user "User.Comments")
		(21 "Eco1.User" user "User.Eco1")
		(23 "Eco2.User" user "User.Eco2")
		(25 "Edge.Cuts" user "Board Geometry/Outline")
		(27 "Margin" user)
		(31 "F.CrtYd" user "Package Geometry/Place Bound Top")
		(29 "B.CrtYd" user "Package Geometry/Place Bound Bottom")
		(35 "F.Fab" user "Ref Des/Assembly Top")
		(33 "B.Fab" user "Ref Des/Assembly Bottom")
	)
	(footprint ""
		(layer "B.Cu")
		(at 29.699458 -142.477236 90)
		(property "Reference" "J9L2"
			(at 2.403348 38.118542 0)
			(unlocked yes)
			(layer "B.SilkS")
			(effects
				(font
					(size 0.7874 0.5842)
					(thickness 0.1524)
				)
				(justify left mirror)
			)
		)
		(property "Value" ""
			(at 0 0 90)
			(layer "B.Fab")
			(effects
				(font
					(size 1.27 1.27)
				)
				(justify mirror)
			)
		)
		(duplicate_pad_numbers_are_jumpers no)
		(pad "199" smd rect
			(at -4.59994 45.900086 270)
			(size 1.8034 0.508)
			(layers "B.Cu" "B.Mask" "B.Paste")
			(net "M_L_ECC<7>")
		)
		(pad "200" smd rect
			(at -4.59994 46.74997 270)
			(size 1.8034 0.508)
			(layers "B.Cu" "B.Mask" "B.Paste")
			(net "GND")
		)
		(pad "201" smd rect
			(at -4.59994 47.600108 270)
			(size 1.8034 0.508)
			(layers "B.Cu" "B.Mask" "B.Paste")
			(net "M_L_ECC<3>")
		)
		(pad "202" smd rect
			(at -4.59994 48.449992 270)
			(size 1.8034 0.508)
			(layers "B.Cu" "B.Mask" "B.Paste")
			(net "GND")
		)
		(pad "203" smd rect
			(at -4.59994 49.299876 270)
			(size 1.8034 0.508)
			(layers "B.Cu" "B.Mask" "B.Paste")
			(net "M_L_CKE<3>")
		)
		(pad "204" smd rect
			(at -4.59994 50.150014 270)
			(size 1.8034 0.508)
			(layers "B.Cu" "B.Mask" "B.Paste")
			(net "PVDDQ_KLM")
		)
		(pad "205" smd rect
			(at -4.59994 50.999898 270)
			(size 1.8034 0.508)
			(layers "B.Cu" "B.Mask" "B.Paste")
			(net "TP_CH_L_DIMM0_RFU_0")
		)
		(pad "206" smd rect
			(at -4.59994 51.850036 270)
			(size 1.8034 0.508)
			(layers "B.Cu" "B.Mask" "B.Paste")
			(net "PVDDQ_KLM")
		)
		(pad "207" smd rect
			(at -4.59994 52.69992 270)
			(size 1.8034 0.508)
			(layers "B.Cu" "B.Mask" "B.Paste")
			(net "M_L_BG<1>")
		)
		(pad "208" smd rect
			(at -4.59994 53.550058 270)
			(size 1.8034 0.508)
			(layers "B.Cu" "B.Mask" "B.Paste")
			(net "M_L_ALERT_N")
		)
		(pad "209" smd rect
			(at -4.59994 54.399942 270)
			(size 1.8034 0.508)
			(layers "B.Cu" "B.Mask" "B.Paste")
			(net "PVDDQ_KLM")
		)
		(pad "210" smd rect
			(at -4.59994 55.25008 270)
			(size 1.8034 0.508)
			(layers "B.Cu" "B.Mask" "B.Paste")
			(net "M_L_MA<11>")
		)
		(pad "211" smd rect
			(at -4.59994 56.099964 270)
			(size 1.8034 0.508)
			(layers "B.Cu" "B.Mask" "B.Paste")
			(net "M_L_MA<7>")
		)
		(pad "212" smd rect
			(at -4.59994 56.950102 270)
			(size 1.8034 0.508)
			(layers "B.Cu" "B.Mask" "B.Paste")
			(net "PVDDQ_KLM")
		)
		(pad "213" smd rect
			(at -4.59994 57.799986 270)
			(size 1.8034 0.508)
			(layers "B.Cu" "B.Mask" "B.Paste")
			(net "M_L_MA<5>")
		)
		(pad "214" smd rect
			(at -4.59994 58.650124 270)
			(size 1.8034 0.508)
			(layers "B.Cu" "B.Mask" "B.Paste")
			(net "M_L_MA<4>")
		)
		(pad "215" smd rect
			(at -4.59994 59.500008 270)
			(size 1.8034 0.508)
			(layers "B.Cu" "B.Mask" "B.Paste")
			(net "PVDDQ_KLM")
		)
		(pad "216" smd rect
			(at -4.59994 60.349892 270)
			(size 1.8034 0.508)
			(layers "B.Cu" "B.Mask" "B.Paste")
			(net "M_L_MA<2>")
		)
		(pad "217" smd rect
			(at -4.59994 61.20003 270)
			(size 1.8034 0.508)
			(layers "B.Cu" "B.Mask" "B.Paste")
			(net "PVDDQ_KLM")
		)
		(pad "218" smd rect
			(at -4.59994 62.049914 270)
			(size 1.8034 0.508)
			(layers "B.Cu" "B.Mask" "B.Paste")
			(net "M_L_CLK_DP<3>")
		)
		(pad "219" smd rect
			(at -4.59994 62.900052 270)
			(size 1.8034 0.508)
			(layers "B.Cu" "B.Mask" "B.Paste")
			(net "M_L_CLK_DN<3>")
		)
		(pad "220" smd rect
			(at -4.59994 63.749936 270)
			(size 1.8034 0.508)
			(layers "B.Cu" "B.Mask" "B.Paste")
			(net "PVDDQ_KLM")
		)
		(pad "221" smd rect
			(at -4.59994 64.600074 270)
			(size 1.8034 0.508)
			(layers "B.Cu" "B.Mask" "B.Paste")
			(net "PVTT_KLM")
		)
		(pad "222" smd rect
			(at -4.59994 70.550024 270)
			(size 1.8034 0.508)
			(layers "B.Cu" "B.Mask" "B.Paste")
			(net "M_L_PAR")
		)
		(pad "223" smd rect
			(at -4.59994 71.399908 270)
			(size 1.8034 0.508)
			(layers "B.Cu" "B.Mask" "B.Paste")
			(net "PVDDQ_KLM")
		)
		(pad "224" smd rect
			(at -4.59994 72.250046 270)
			(size 1.8034 0.508)
			(layers "B.Cu" "B.Mask" "B.Paste")
			(net "M_L_BA<1>")
		)
		(pad "225" smd rect
			(at -4.59994 73.09993 270)
			(size 1.8034 0.508)
			(layers "B.Cu" "B.Mask" "B.Paste")
			(net "M_L_MA<10>")
		)
		(pad "226" smd rect
			(at -4.59994 73.950068 270)
			(size 1.8034 0.508)
			(layers "B.Cu" "B.Mask" "B.Paste")
			(net "PVDDQ_KLM")
		)
		(pad "227" smd rect
			(at -4.59994 74.799952 270)
			(size 1.8034 0.508)
			(layers "B.Cu" "B.Mask" "B.Paste")
			(net "TP_CH_L_DIMM0_RFU_1")
		)
		(pad "228" smd rect
			(at -4.59994 75.65009 270)
			(size 1.8034 0.508)
			(layers "B.Cu" "B.Mask" "B.Paste")
			(net "M_L_MA<14>")
		)
		(pad "229" smd rect
			(at -4.59994 76.499974 270)
			(size 1.8034 0.508)
			(layers "B.Cu" "B.Mask" "B.Paste")
			(net "PVDDQ_KLM")
		)
		(pad "230" smd rect
			(at -4.59994 77.350112 270)
			(size 1.8034 0.508)
			(layers "B.Cu" "B.Mask" "B.Paste")
			(net "FM_ADR_COMPLETE_KLM_N")
		)
		(pad "231" smd rect
			(at -4.59994 78.199996 270)
			(size 1.8034 0.508)
			(layers "B.Cu" "B.Mask" "B.Paste")
			(net "PVDDQ_KLM")
		)
		(pad "232" smd rect
			(at -4.59994 79.04988 270)
			(size 1.8034 0.508)
			(layers "B.Cu" "B.Mask" "B.Paste")
			(net "M_L_MA<13>")
		)
		(pad "233" smd rect
			(at -4.59994 79.900018 270)
			(size 1.8034 0.508)
			(layers "B.Cu" "B.Mask" "B.Paste")
			(net "PVDDQ_KLM")
		)
		(pad "234" smd rect
			(at -4.59994 80.749902 270)
			(size 1.8034 0.508)
			(layers "B.Cu" "B.Mask" "B.Paste")
			(net "M_L_MA<17>")
		)
		(pad "235" smd rect
			(at -4.59994 81.60004 270)
			(size 1.8034 0.508)
			(layers "B.Cu" "B.Mask" "B.Paste")
			(net "M_L_C<2>")
		)
		(pad "236" smd rect
			(at -4.59994 82.449924 270)
			(size 1.8034 0.508)
			(layers "B.Cu" "B.Mask" "B.Paste")
			(net "PVDDQ_KLM")
		)
		(pad "237" smd rect
			(at -4.59994 83.300062 270)
			(size 1.8034 0.508)
			(layers "B.Cu" "B.Mask" "B.Paste")
			(net "M_L_CS_N<7>")
		)
		(pad "238" smd rect
			(at -4.59994 84.149946 270)
			(size 1.8034 0.508)
			(layers "B.Cu" "B.Mask" "B.Paste")
			(net "GND")
		)
		(pad "239" smd rect
			(at -4.59994 85.000084 270)
			(size 1.8034 0.508)
			(layers "B.Cu" "B.Mask" "B.Paste")
			(net "GND")
		)
		(pad "240" smd rect
			(at -4.59994 85.849968 270)
			(size 1.8034 0.508)
			(layers "B.Cu" "B.Mask" "B.Paste")
			(net "M_L_DQ<37>")
		)
		(pad "241" smd rect
			(at -4.59994 86.700106 270)
			(size 1.8034 0.508)
			(layers "B.Cu" "B.Mask" "B.Paste")
			(net "GND")
		)
		(pad "242" smd rect
			(at -4.59994 87.54999 270)
			(size 1.8034 0.508)
			(layers "B.Cu" "B.Mask" "B.Paste")
			(net "M_L_DQ<33>")
		)
		(pad "243" smd rect
			(at -4.59994 88.399874 270)
			(size 1.8034 0.508)
			(layers "B.Cu" "B.Mask" "B.Paste")
			(net "GND")
		)
		(pad "244" smd rect
			(at -4.59994 89.250012 270)
			(size 1.8034 0.508)
			(layers "B.Cu" "B.Mask" "B.Paste")
			(net "M_L_DQS_DN<4>")
		)
		(pad "245" smd rect
			(at -4.59994 90.099896 270)
			(size 1.8034 0.508)
			(layers "B.Cu" "B.Mask" "B.Paste")
			(net "M_L_DQS_DP<4>")
		)
		(pad "246" smd rect
			(at -4.59994 90.950034 270)
			(size 1.8034 0.508)
			(layers "B.Cu" "B.Mask" "B.Paste")
			(net "GND")
		)
	)
)
